# T6G (Grand Teton) — schematic netlist excerpt (pin names and nets, part order shuffled) for the footprints in the layout excerpt that follows; sources: Cadence DE-HDL packaged netlist, KiCad conversion of 04192023_DAF0TMB3IC0_F0TG_MB_C_brd_V02_OCP.brd

R4567  Q_RES  5.11K 1% CHIP  pkg 0402LF  page 257 : A = P3V3_PDB_AUX_ADC ; B = P1V581_PDB_ADC

PR6001  Q_SP_RES4P  0.0003 1% CHIP  pkg R2725_4P  page 266
  \1a\  = P12V_PSU
  \1b\  = P12V_HSC_SENSE2_R1_P
  \2a\  = P12V_MAIN_R
  \2b\  = P12V_HSC_SENSE2_R1_N

(kicad_pcb
	(version 20260206)
	(generator "pcbnew")
	(generator_version "10.0")
	(general
		(thickness 1.6)
		(legacy_teardrops no)
	)
	(paper "A4")
	(title_block
		(title "04192023_DAF0TMB3IC0_F0TG_MB_C_brd_V02_OCP.brd")
		(comment 1 "Grand Teton / footprints 2802-2803 of 8354")
	)
	(layers
		(0 "F.Cu" signal "TOP")
		(4 "In1.Cu" signal "GND")
		(6 "In2.Cu" signal "IN1")
		(8 "In3.Cu" signal "GND1")
		(10 "In4.Cu" signal "IN2")
		(12 "In5.Cu" signal "GND2")
		(14 "In6.Cu" signal "IN3")
		(16 "In7.Cu" signal "GND3")
		(18 "In8.Cu" signal "VCC")
		(20 "In9.Cu" signal "VCC1")
		(22 "In10.Cu" signal "GND4")
		(24 "In11.Cu" signal "IN4")
		(26 "In12.Cu" signal "GND5")
		(28 "In13.Cu" signal "IN5")
		(30 "In14.Cu" signal "GND6")
		(32 "In15.Cu" signal "IN6")
		(34 "In16.Cu" signal "GND7")
		(2 "B.Cu" signal "BOTTOM")
		(9 "F.Adhes" user "F.Adhesive")
		(11 "B.Adhes" user "B.Adhesive")
		(13 "F.Paste" user "Package Geometry/Pastemask Top")
		(15 "B.Paste" user "Package Geometry/Pastemask Bottom")
		(5 "F.SilkS" user "Ref Des/Silkscreen Top")
		(7 "B.SilkS" user "Ref Des/Silkscreen Bottom")
		(1 "F.Mask" user "Board Geometry/Soldermask Top")
		(3 "B.Mask" user "Board Geometry/Soldermask Bottom")
		(17 "Dwgs.User" user "User.Drawings")
		(19 "Cmts.User" user "User.Comments")
		(21 "Eco1.User" user "User.Eco1")
		(23 "Eco2.User" user "User.Eco2")
		(25 "Edge.Cuts" user "Board Geometry/Outline")
		(27 "Margin" user)
		(31 "F.CrtYd" user "Package Geometry/Place Bound Top")
		(29 "B.CrtYd" user "Package Geometry/Place Bound Bottom")
		(35 "F.Fab" user "Ref Des/Assembly Top")
		(33 "B.Fab" user "Ref Des/Assembly Bottom")
	)
	(footprint ""
		(layer "F.Cu")
		(at 323.624194 -39.12362 180)
		(property "Reference" "R4567"
			(at 0 0 180)
			(layer "F.SilkS")
			(hide yes)
			(effects
				(font
					(size 1.27 1.27)
				)
			)
		)
		(property "Value" ""
			(at 0 0 180)
			(layer "F.Fab")
			(effects
				(font
					(size 1.27 1.27)
				)
			)
		)
		(duplicate_pad_numbers_are_jumpers no)
		(fp_line
			(start 0.7874 0.4064)
			(end -0.7874 0.4064)
			(stroke
				(width 0.1524)
				(type default)
			)
			(layer "F.SilkS")
		)
		(fp_line
			(start 0.7874 -0.4064)
			(end 0.7874 0.4064)
			(stroke
				(width 0.1524)
				(type default)
			)
			(layer "F.SilkS")
		)
		(fp_line
			(start -0.7874 0.4064)
			(end -0.7874 -0.4064)
			(stroke
				(width 0.1524)
				(type default)
			)
			(layer "F.SilkS")
		)
		(fp_line
			(start -0.7874 -0.4064)
			(end 0.7874 -0.4064)
			(stroke
				(width 0.1524)
				(type default)
			)
			(layer "F.SilkS")
		)
		(fp_line
			(start 0.67945 0.3048)
			(end 0.120396 0.3048)
			(stroke
				(width 0.1)
				(type default)
			)
			(layer "F.Fab")
		)
		(fp_line
			(start 0.67945 -0.3048)
			(end 0.67945 0.3048)
			(stroke
				(width 0.1)
				(type default)
			)
			(layer "F.Fab")
		)
		(fp_line
			(start 0.12065 -0.2794)
			(end 0.12065 -0.3048)
			(stroke
				(width 0.1)
				(type default)
			)
			(layer "F.Fab")
		)
		(fp_line
			(start 0.12065 -0.3048)
			(end 0.67945 -0.3048)
			(stroke
				(width 0.1)
				(type default)
			)
			(layer "F.Fab")
		)
		(fp_line
			(start 0.120396 0.3048)
			(end 0.120396 0.2794)
			(stroke
				(width 0.1)
				(type default)
			)
			(layer "F.Fab")
		)
		(fp_line
			(start 0.120396 0.2794)
			(end -0.12065 0.2794)
			(stroke
				(width 0.1)
				(type default)
			)
			(layer "F.Fab")
		)
		(fp_line
			(start -0.12065 0.3048)
			(end -0.67945 0.3048)
			(stroke
				(width 0.1)
				(type default)
			)
			(layer "F.Fab")
		)
		(fp_line
			(start -0.12065 0.2794)
			(end -0.12065 0.3048)
			(stroke
				(width 0.1)
				(type default)
			)
			(layer "F.Fab")
		)
		(fp_line
			(start -0.12065 -0.2794)
			(end 0.12065 -0.2794)
			(stroke
				(width 0.1)
				(type default)
			)
			(layer "F.Fab")
		)
		(fp_line
			(start -0.12065 -0.305054)
			(end -0.12065 -0.2794)
			(stroke
				(width 0.1)
				(type default)
			)
			(layer "F.Fab")
		)
		(fp_line
			(start -0.67945 0.3048)
			(end -0.67945 -0.305054)
			(stroke
				(width 0.1)
				(type default)
			)
			(layer "F.Fab")
		)
		(fp_line
			(start -0.67945 -0.305054)
			(end -0.12065 -0.305054)
			(stroke
				(width 0.1)
				(type default)
			)
			(layer "F.Fab")
		)
		(pad "1" smd circle
			(at -0.40005 0 180)
			(size 0 0)
			(layers "F.Cu" "F.Mask" "F.Paste")
			(net "P3V3_PDB_AUX_ADC")
		)
		(pad "2" smd circle
			(at 0.40005 0 180)
			(size 0 0)
			(layers "F.Cu" "F.Mask" "F.Paste")
			(net "P1V581_PDB_ADC")
		)
	)
	(footprint ""
		(layer "F.Cu")
		(at 244.115336 -393.909296 -90)
		(property "Reference" "PR6001"
			(at -4.524248 3.668268 90)
			(unlocked yes)
			(layer "F.SilkS")
			(effects
				(font
					(size 0.7874 0.5842)
					(thickness 0.1524)
				)
				(justify left)
			)
		)
		(property "Value" ""
			(at 0 0 270)
			(layer "F.Fab")
			(effects
				(font
					(size 1.27 1.27)
				)
			)
		)
		(duplicate_pad_numbers_are_jumpers no)
		(fp_line
			(start -3.9878 3.5814)
			(end -3.9878 -3.5814)
			(stroke
				(width 0.1524)
				(type default)
			)
			(layer "F.SilkS")
		)
		(fp_line
			(start 3.9878 3.5814)
			(end -3.9878 3.5814)
			(stroke
				(width 0.1524)
				(type default)
			)
			(layer "F.SilkS")
		)
		(fp_line
			(start -3.9878 -3.5814)
			(end 3.9878 -3.5814)
			(stroke
				(width 0.1524)
				(type default)
			)
			(layer "F.SilkS")
		)
		(fp_line
			(start 3.9878 -3.5814)
			(end 3.9878 3.5814)
			(stroke
				(width 0.1524)
				(type default)
			)
			(layer "F.SilkS")
		)
		(fp_line
			(start -3.5306 3.353054)
			(end -3.5306 -3.353054)
			(stroke
				(width 0.1)
				(type default)
			)
			(layer "F.Fab")
		)
		(fp_line
			(start 3.5306 3.353054)
			(end -3.5306 3.353054)
			(stroke
				(width 0.1)
				(type default)
			)
			(layer "F.Fab")
		)
		(fp_line
			(start -3.5306 -3.353054)
			(end 3.5306 -3.353054)
			(stroke
				(width 0.1)
				(type default)
			)
			(layer "F.Fab")
		)
		(fp_line
			(start 3.5306 -3.353054)
			(end 3.5306 3.353054)
			(stroke
				(width 0.1)
				(type default)
			)
			(layer "F.Fab")
		)
		(pad "1A" smd rect
			(at -2.249932 0 90)
			(size 3.2004 6.858)
			(layers "F.Cu" "F.Mask" "F.Paste")
			(net "P12V_PSU")
		)
		(pad "1B" smd rect
			(at -0.776732 0 270)
			(size 0.254 0.508)
			(layers "F.Cu" "F.Mask" "F.Paste")
			(net "P12V_HSC_SENSE2_R1_P")
		)
		(pad "2A" smd rect
			(at 2.249932 0 90)
			(size 3.2004 6.858)
			(layers "F.Cu" "F.Mask" "F.Paste")
			(net "P12V_MAIN_R")
		)
		(pad "2B" smd rect
			(at 0.776732 0 270)
			(size 0.254 0.508)
			(layers "F.Cu" "F.Mask" "F.Paste")
			(net "P12V_HSC_SENSE2_R1_N")
		)
	)
)
